(kicad_pcb
	(version 20260206)
	(generator "pcbnew")
	(generator_version "10.0")
	(general
		(thickness 1.6)
		(legacy_teardrops no)
	)
	(paper "A4")
	(title_block
		(title "03242023_DA0F0TMBIJ0_F0T_Motherboard_J_brd_V01_OCP.brd")
		(comment 1 "Grand Teton / footprints 4257-4263 of 6105")
	)
	(layers
		(0 "F.Cu" signal "TOP")
		(4 "In1.Cu" signal "GND")
		(6 "In2.Cu" signal "IN1")
		(8 "In3.Cu" signal "GND1")
		(10 "In4.Cu" signal "IN2")
		(12 "In5.Cu" signal "GND2")
		(14 "In6.Cu" signal "IN3")
		(16 "In7.Cu" signal "GND3")
		(18 "In8.Cu" signal "VCC")
		(20 "In9.Cu" signal "VCC1")
		(22 "In10.Cu" signal "GND4")
		(24 "In11.Cu" signal "IN4")
		(26 "In12.Cu" signal "GND5")
		(28 "In13.Cu" signal "IN5")
		(30 "In14.Cu" signal "GND6")
		(32 "In15.Cu" signal "IN6")
		(34 "In16.Cu" signal "GND7")
		(2 "B.Cu" signal "BOTTOM")
		(9 "F.Adhes" user "F.Adhesive")
		(11 "B.Adhes" user "B.Adhesive")
		(13 "F.Paste" user "Package Geometry/Pastemask Top")
		(15 "B.Paste" user "Package Geometry/Pastemask Bottom")
		(5 "F.SilkS" user "Ref Des/Silkscreen Top")
		(7 "B.SilkS" user "Ref Des/Silkscreen Bottom")
		(1 "F.Mask" user "Board Geometry/Soldermask Top")
		(3 "B.Mask" user "Board Geometry/Soldermask Bottom")
		(17 "Dwgs.User" user "User.Drawings")
		(19 "Cmts.User" user "User.Comments")
		(21 "Eco1.User" user "User.Eco1")
		(23 "Eco2.User" user "User.Eco2")
		(25 "Edge.Cuts" user "Board Geometry/Outline")
		(27 "Margin" user)
		(31 "F.CrtYd" user "Package Geometry/Place Bound Top")
		(29 "B.CrtYd" user "Package Geometry/Place Bound Bottom")
		(35 "F.Fab" user "Ref Des/Assembly Top")
		(33 "B.Fab" user "Ref Des/Assembly Bottom")
	)
	(footprint ""
		(layer "B.Cu")
		(at 358.80421 -357.578406)
		(property "Reference" "PR171"
			(at 0 0 0)
			(layer "B.SilkS")
			(hide yes)
			(effects
				(font
					(size 1.27 1.27)
				)
				(justify mirror)
			)
		)
		(property "Value" ""
			(at 0 0 0)
			(layer "B.Fab")
			(effects
				(font
					(size 1.27 1.27)
				)
				(justify mirror)
			)
		)
		(duplicate_pad_numbers_are_jumpers no)
		(fp_line
			(start -0.7874 -0.4064)
			(end -0.7874 0.4064)
			(stroke
				(width 0.1524)
				(type default)
			)
			(layer "B.SilkS")
		)
		(fp_line
			(start -0.7874 0.4064)
			(end 0.7874 0.4064)
			(stroke
				(width 0.1524)
				(type default)
			)
			(layer "B.SilkS")
		)
		(fp_line
			(start 0.7874 -0.4064)
			(end -0.7874 -0.4064)
			(stroke
				(width 0.1524)
				(type default)
			)
			(layer "B.SilkS")
		)
		(fp_line
			(start 0.7874 0.4064)
			(end 0.7874 -0.4064)
			(stroke
				(width 0.1524)
				(type default)
			)
			(layer "B.SilkS")
		)
		(fp_line
			(start -0.67945 -0.3048)
			(end -0.67945 0.3048)
			(stroke
				(width 0.1)
				(type default)
			)
			(layer "B.Fab")
		)
		(fp_line
			(start -0.67945 0.3048)
			(end -0.120396 0.3048)
			(stroke
				(width 0.1)
				(type default)
			)
			(layer "B.Fab")
		)
		(fp_line
			(start -0.12065 -0.3048)
			(end -0.67945 -0.3048)
			(stroke
				(width 0.1)
				(type default)
			)
			(layer "B.Fab")
		)
		(fp_line
			(start -0.12065 -0.2794)
			(end -0.12065 -0.3048)
			(stroke
				(width 0.1)
				(type default)
			)
			(layer "B.Fab")
		)
		(fp_line
			(start -0.120396 0.2794)
			(end 0.12065 0.2794)
			(stroke
				(width 0.1)
				(type default)
			)
			(layer "B.Fab")
		)
		(fp_line
			(start -0.120396 0.3048)
			(end -0.120396 0.2794)
			(stroke
				(width 0.1)
				(type default)
			)
			(layer "B.Fab")
		)
		(fp_line
			(start 0.12065 -0.305054)
			(end 0.12065 -0.2794)
			(stroke
				(width 0.1)
				(type default)
			)
			(layer "B.Fab")
		)
		(fp_line
			(start 0.12065 -0.2794)
			(end -0.12065 -0.2794)
			(stroke
				(width 0.1)
				(type default)
			)
			(layer "B.Fab")
		)
		(fp_line
			(start 0.12065 0.2794)
			(end 0.12065 0.3048)
			(stroke
				(width 0.1)
				(type default)
			)
			(layer "B.Fab")
		)
		(fp_line
			(start 0.12065 0.3048)
			(end 0.67945 0.3048)
			(stroke
				(width 0.1)
				(type default)
			)
			(layer "B.Fab")
		)
		(fp_line
			(start 0.67945 -0.305054)
			(end 0.12065 -0.305054)
			(stroke
				(width 0.1)
				(type default)
			)
			(layer "B.Fab")
		)
		(fp_line
			(start 0.67945 0.3048)
			(end 0.67945 -0.305054)
			(stroke
				(width 0.1)
				(type default)
			)
			(layer "B.Fab")
		)
		(pad "1" smd circle
			(at 0.40005 0 180)
			(size 0 0)
			(layers "B.Cu" "B.Mask" "B.Paste")
			(net "PVCCIN_CPU0_ADDR")
		)
		(pad "2" smd circle
			(at -0.40005 0 180)
			(size 0 0)
			(layers "B.Cu" "B.Mask" "B.Paste")
			(net "GND")
		)
	)
	(footprint ""
		(layer "B.Cu")
		(at 177.443638 -13.762228 90)
		(property "Reference" "R2423"
			(at 0 0 90)
			(layer "B.SilkS")
			(hide yes)
			(effects
				(font
					(size 1.27 1.27)
				)
				(justify mirror)
			)
		)
		(property "Value" ""
			(at 0 0 90)
			(layer "B.Fab")
			(effects
				(font
					(size 1.27 1.27)
				)
				(justify mirror)
			)
		)
		(duplicate_pad_numbers_are_jumpers no)
		(fp_line
			(start 0.7874 -0.4064)
			(end -0.7874 -0.4064)
			(stroke
				(width 0.1524)
				(type default)
			)
			(layer "B.SilkS")
		)
		(fp_line
			(start -0.7874 -0.4064)
			(end -0.7874 0.4064)
			(stroke
				(width 0.1524)
				(type default)
			)
			(layer "B.SilkS")
		)
		(fp_line
			(start 0.7874 0.4064)
			(end 0.7874 -0.4064)
			(stroke
				(width 0.1524)
				(type default)
			)
			(layer "B.SilkS")
		)
		(fp_line
			(start -0.7874 0.4064)
			(end 0.7874 0.4064)
			(stroke
				(width 0.1524)
				(type default)
			)
			(layer "B.SilkS")
		)
		(fp_line
			(start 0.67945 -0.305054)
			(end 0.12065 -0.305054)
			(stroke
				(width 0.1)
				(type default)
			)
			(layer "B.Fab")
		)
		(fp_line
			(start 0.12065 -0.305054)
			(end 0.12065 -0.2794)
			(stroke
				(width 0.1)
				(type default)
			)
			(layer "B.Fab")
		)
		(fp_line
			(start -0.12065 -0.3048)
			(end -0.67945 -0.3048)
			(stroke
				(width 0.1)
				(type default)
			)
			(layer "B.Fab")
		)
		(fp_line
			(start -0.67945 -0.3048)
			(end -0.67945 0.3048)
			(stroke
				(width 0.1)
				(type default)
			)
			(layer "B.Fab")
		)
		(fp_line
			(start 0.12065 -0.2794)
			(end -0.12065 -0.2794)
			(stroke
				(width 0.1)
				(type default)
			)
			(layer "B.Fab")
		)
		(fp_line
			(start -0.12065 -0.2794)
			(end -0.12065 -0.3048)
			(stroke
				(width 0.1)
				(type default)
			)
			(layer "B.Fab")
		)
		(fp_line
			(start 0.12065 0.2794)
			(end 0.12065 0.3048)
			(stroke
				(width 0.1)
				(type default)
			)
			(layer "B.Fab")
		)
		(fp_line
			(start -0.120396 0.2794)
			(end 0.12065 0.2794)
			(stroke
				(width 0.1)
				(type default)
			)
			(layer "B.Fab")
		)
		(fp_line
			(start 0.67945 0.3048)
			(end 0.67945 -0.305054)
			(stroke
				(width 0.1)
				(type default)
			)
			(layer "B.Fab")
		)
		(fp_line
			(start 0.12065 0.3048)
			(end 0.67945 0.3048)
			(stroke
				(width 0.1)
				(type default)
			)
			(layer "B.Fab")
		)
		(fp_line
			(start -0.120396 0.3048)
			(end -0.120396 0.2794)
			(stroke
				(width 0.1)
				(type default)
			)
			(layer "B.Fab")
		)
		(fp_line
			(start -0.67945 0.3048)
			(end -0.120396 0.3048)
			(stroke
				(width 0.1)
				(type default)
			)
			(layer "B.Fab")
		)
		(pad "1" smd circle
			(at 0.40005 0 270)
			(size 0 0)
			(layers "B.Cu" "B.Mask" "B.Paste")
			(net "SMB_SML1_PMBUS_3V3AUX_PCH_SCL")
		)
		(pad "2" smd circle
			(at -0.40005 0 270)
			(size 0 0)
			(layers "B.Cu" "B.Mask" "B.Paste")
			(net "SMB_SML1_PMBUS_3V3AUX_PCH_SCL_R")
		)
	)
	(footprint ""
		(layer "B.Cu")
		(at 119.95912 -255.8542 -90)
		(property "Reference" "C335"
			(at 0 0 90)
			(layer "B.SilkS")
			(hide yes)
			(effects
				(font
					(size 1.27 1.27)
				)
				(justify mirror)
			)
		)
		(property "Value" ""
			(at 0 0 90)
			(layer "B.Fab")
			(effects
				(font
					(size 1.27 1.27)
				)
				(justify mirror)
			)
		)
		(duplicate_pad_numbers_are_jumpers no)
		(fp_line
			(start -1.524 0.762)
			(end 1.524 0.762)
			(stroke
				(width 0.1524)
				(type default)
			)
			(layer "B.SilkS")
		)
		(fp_line
			(start 1.524 0.762)
			(end 1.524 -0.762)
			(stroke
				(width 0.1524)
				(type default)
			)
			(layer "B.SilkS")
		)
		(fp_line
			(start -1.524 -0.762)
			(end -1.524 0.762)
			(stroke
				(width 0.1524)
				(type default)
			)
			(layer "B.SilkS")
		)
		(fp_line
			(start 1.524 -0.762)
			(end -1.524 -0.762)
			(stroke
				(width 0.1524)
				(type default)
			)
			(layer "B.SilkS")
		)
		(fp_line
			(start -1.1049 0.724916)
			(end -1.1049 -0.724916)
			(stroke
				(width 0.1)
				(type default)
			)
			(layer "B.Fab")
		)
		(fp_line
			(start 1.1049 0.724916)
			(end -1.1049 0.724916)
			(stroke
				(width 0.1)
				(type default)
			)
			(layer "B.Fab")
		)
		(fp_line
			(start -1.1049 -0.724916)
			(end 1.1049 -0.724916)
			(stroke
				(width 0.1)
				(type default)
			)
			(layer "B.Fab")
		)
		(fp_line
			(start 1.1049 -0.724916)
			(end 1.1049 0.724916)
			(stroke
				(width 0.1)
				(type default)
			)
			(layer "B.Fab")
		)
		(pad "1" smd rect
			(at 0.889 0 270)
			(size 1.016 1.27)
			(layers "B.Cu" "B.Mask" "B.Paste")
			(net "PVCCIN_CPU1")
		)
		(pad "2" smd rect
			(at -0.889 0 270)
			(size 1.016 1.27)
			(layers "B.Cu" "B.Mask" "B.Paste")
			(net "GND")
		)
	)
	(footprint ""
		(layer "B.Cu")
		(at 36.583366 -192.924176 -90)
		(property "Reference" "R816"
			(at 0 0 90)
			(layer "B.SilkS")
			(hide yes)
			(effects
				(font
					(size 1.27 1.27)
				)
				(justify mirror)
			)
		)
		(property "Value" ""
			(at 0 0 90)
			(layer "B.Fab")
			(effects
				(font
					(size 1.27 1.27)
				)
				(justify mirror)
			)
		)
		(duplicate_pad_numbers_are_jumpers no)
		(fp_line
			(start -0.7874 0.4064)
			(end 0.7874 0.4064)
			(stroke
				(width 0.1524)
				(type default)
			)
			(layer "B.SilkS")
		)
		(fp_line
			(start 0.7874 0.4064)
			(end 0.7874 -0.4064)
			(stroke
				(width 0.1524)
				(type default)
			)
			(layer "B.SilkS")
		)
		(fp_line
			(start -0.7874 -0.4064)
			(end -0.7874 0.4064)
			(stroke
				(width 0.1524)
				(type default)
			)
			(layer "B.SilkS")
		)
		(fp_line
			(start 0.7874 -0.4064)
			(end -0.7874 -0.4064)
			(stroke
				(width 0.1524)
				(type default)
			)
			(layer "B.SilkS")
		)
		(fp_line
			(start -0.67945 0.3048)
			(end -0.120396 0.3048)
			(stroke
				(width 0.1)
				(type default)
			)
			(layer "B.Fab")
		)
		(fp_line
			(start -0.120396 0.3048)
			(end -0.120396 0.2794)
			(stroke
				(width 0.1)
				(type default)
			)
			(layer "B.Fab")
		)
		(fp_line
			(start 0.12065 0.3048)
			(end 0.67945 0.3048)
			(stroke
				(width 0.1)
				(type default)
			)
			(layer "B.Fab")
		)
		(fp_line
			(start 0.67945 0.3048)
			(end 0.67945 -0.305054)
			(stroke
				(width 0.1)
				(type default)
			)
			(layer "B.Fab")
		)
		(fp_line
			(start -0.120396 0.2794)
			(end 0.12065 0.2794)
			(stroke
				(width 0.1)
				(type default)
			)
			(layer "B.Fab")
		)
		(fp_line
			(start 0.12065 0.2794)
			(end 0.12065 0.3048)
			(stroke
				(width 0.1)
				(type default)
			)
			(layer "B.Fab")
		)
		(fp_line
			(start -0.12065 -0.2794)
			(end -0.12065 -0.3048)
			(stroke
				(width 0.1)
				(type default)
			)
			(layer "B.Fab")
		)
		(fp_line
			(start 0.12065 -0.2794)
			(end -0.12065 -0.2794)
			(stroke
				(width 0.1)
				(type default)
			)
			(layer "B.Fab")
		)
		(fp_line
			(start -0.67945 -0.3048)
			(end -0.67945 0.3048)
			(stroke
				(width 0.1)
				(type default)
			)
			(layer "B.Fab")
		)
		(fp_line
			(start -0.12065 -0.3048)
			(end -0.67945 -0.3048)
			(stroke
				(width 0.1)
				(type default)
			)
			(layer "B.Fab")
		)
		(fp_line
			(start 0.12065 -0.305054)
			(end 0.12065 -0.2794)
			(stroke
				(width 0.1)
				(type default)
			)
			(layer "B.Fab")
		)
		(fp_line
			(start 0.67945 -0.305054)
			(end 0.12065 -0.305054)
			(stroke
				(width 0.1)
				(type default)
			)
			(layer "B.Fab")
		)
		(pad "1" smd circle
			(at 0.40005 0 90)
			(size 0 0)
			(layers "B.Cu" "B.Mask" "B.Paste")
			(net "RST_PLD_CPU1_DRAM_AB_N")
		)
		(pad "2" smd circle
			(at -0.40005 0 90)
			(size 0 0)
			(layers "B.Cu" "B.Mask" "B.Paste")
			(net "RST_M_AB_CPU1_FPGA_N")
		)
	)
	(footprint ""
		(layer "B.Cu")
		(at 376.468132 -74.614024 180)
		(property "Reference" "PC1240"
			(at 0 0 0)
			(layer "B.SilkS")
			(hide yes)
			(effects
				(font
					(size 1.27 1.27)
				)
				(justify mirror)
			)
		)
		(property "Value" ""
			(at 0 0 0)
			(layer "B.Fab")
			(effects
				(font
					(size 1.27 1.27)
				)
				(justify mirror)
			)
		)
		(duplicate_pad_numbers_are_jumpers no)
		(fp_line
			(start 1.524 0.762)
			(end 1.524 -0.762)
			(stroke
				(width 0.1524)
				(type default)
			)
			(layer "B.SilkS")
		)
		(fp_line
			(start 1.524 -0.762)
			(end -1.524 -0.762)
			(stroke
				(width 0.1524)
				(type default)
			)
			(layer "B.SilkS")
		)
		(fp_line
			(start -1.524 0.762)
			(end 1.524 0.762)
			(stroke
				(width 0.1524)
				(type default)
			)
			(layer "B.SilkS")
		)
		(fp_line
			(start -1.524 -0.762)
			(end -1.524 0.762)
			(stroke
				(width 0.1524)
				(type default)
			)
			(layer "B.SilkS")
		)
		(fp_line
			(start 1.1049 0.724916)
			(end -1.1049 0.724916)
			(stroke
				(width 0.1)
				(type default)
			)
			(layer "B.Fab")
		)
		(fp_line
			(start 1.1049 -0.724916)
			(end 1.1049 0.724916)
			(stroke
				(width 0.1)
				(type default)
			)
			(layer "B.Fab")
		)
		(fp_line
			(start -1.1049 0.724916)
			(end -1.1049 -0.724916)
			(stroke
				(width 0.1)
				(type default)
			)
			(layer "B.Fab")
		)
		(fp_line
			(start -1.1049 -0.724916)
			(end 1.1049 -0.724916)
			(stroke
				(width 0.1)
				(type default)
			)
			(layer "B.Fab")
		)
		(pad "1" smd rect
			(at 0.889 0 180)
			(size 1.016 1.27)
			(layers "B.Cu" "B.Mask" "B.Paste")
			(net "P1V8_PCH_AUX")
		)
		(pad "2" smd rect
			(at -0.889 0 180)
			(size 1.016 1.27)
			(layers "B.Cu" "B.Mask" "B.Paste")
			(net "GND")
		)
	)
	(footprint ""
		(layer "B.Cu")
		(at 110.051596 -324.792086 -90)
		(property "Reference" "PC544_P1_3"
			(at 0 0 90)
			(layer "B.SilkS")
			(hide yes)
			(effects
				(font
					(size 1.27 1.27)
				)
				(justify mirror)
			)
		)
		(property "Value" ""
			(at 0 0 90)
			(layer "B.Fab")
			(effects
				(font
					(size 1.27 1.27)
				)
				(justify mirror)
			)
		)
		(duplicate_pad_numbers_are_jumpers no)
		(fp_line
			(start -1.524 0.762)
			(end 1.524 0.762)
			(stroke
				(width 0.1524)
				(type default)
			)
			(layer "B.SilkS")
		)
		(fp_line
			(start 1.524 0.762)
			(end 1.524 -0.762)
			(stroke
				(width 0.1524)
				(type default)
			)
			(layer "B.SilkS")
		)
		(fp_line
			(start -1.524 -0.762)
			(end -1.524 0.762)
			(stroke
				(width 0.1524)
				(type default)
			)
			(layer "B.SilkS")
		)
		(fp_line
			(start 1.524 -0.762)
			(end -1.524 -0.762)
			(stroke
				(width 0.1524)
				(type default)
			)
			(layer "B.SilkS")
		)
		(fp_line
			(start -1.1049 0.724916)
			(end -1.1049 -0.724916)
			(stroke
				(width 0.1)
				(type default)
			)
			(layer "B.Fab")
		)
		(fp_line
			(start 1.1049 0.724916)
			(end -1.1049 0.724916)
			(stroke
				(width 0.1)
				(type default)
			)
			(layer "B.Fab")
		)
		(fp_line
			(start -1.1049 -0.724916)
			(end 1.1049 -0.724916)
			(stroke
				(width 0.1)
				(type default)
			)
			(layer "B.Fab")
		)
		(fp_line
			(start 1.1049 -0.724916)
			(end 1.1049 0.724916)
			(stroke
				(width 0.1)
				(type default)
			)
			(layer "B.Fab")
		)
		(pad "1" smd rect
			(at 0.889 0 270)
			(size 1.016 1.27)
			(layers "B.Cu" "B.Mask" "B.Paste")
			(net "PVCCIN_CPU1")
		)
		(pad "2" smd rect
			(at -0.889 0 270)
			(size 1.016 1.27)
			(layers "B.Cu" "B.Mask" "B.Paste")
			(net "GND")
		)
	)
	(footprint ""
		(layer "B.Cu")
		(at 289.988498 -403.031452 90)
		(property "Reference" "PR2516"
			(at 0 0 90)
			(layer "B.SilkS")
			(hide yes)
			(effects
				(font
					(size 1.27 1.27)
				)
				(justify mirror)
			)
		)
		(property "Value" ""
			(at 0 0 90)
			(layer "B.Fab")
			(effects
				(font
					(size 1.27 1.27)
				)
				(justify mirror)
			)
		)
		(duplicate_pad_numbers_are_jumpers no)
		(fp_line
			(start 0.7874 -0.4064)
			(end -0.7874 -0.4064)
			(stroke
				(width 0.1524)
				(type default)
			)
			(layer "B.SilkS")
		)
		(fp_line
			(start -0.7874 -0.4064)
			(end -0.7874 0.4064)
			(stroke
				(width 0.1524)
				(type default)
			)
			(layer "B.SilkS")
		)
		(fp_line
			(start 0.7874 0.4064)
			(end 0.7874 -0.4064)
			(stroke
				(width 0.1524)
				(type default)
			)
			(layer "B.SilkS")
		)
		(fp_line
			(start -0.7874 0.4064)
			(end 0.7874 0.4064)
			(stroke
				(width 0.1524)
				(type default)
			)
			(layer "B.SilkS")
		)
		(fp_line
			(start 0.67945 -0.305054)
			(end 0.12065 -0.305054)
			(stroke
				(width 0.1)
				(type default)
			)
			(layer "B.Fab")
		)
		(fp_line
			(start 0.12065 -0.305054)
			(end 0.12065 -0.2794)
			(stroke
				(width 0.1)
				(type default)
			)
			(layer "B.Fab")
		)
		(fp_line
			(start -0.12065 -0.3048)
			(end -0.67945 -0.3048)
			(stroke
				(width 0.1)
				(type default)
			)
			(layer "B.Fab")
		)
		(fp_line
			(start -0.67945 -0.3048)
			(end -0.67945 0.3048)
			(stroke
				(width 0.1)
				(type default)
			)
			(layer "B.Fab")
		)
		(fp_line
			(start 0.12065 -0.2794)
			(end -0.12065 -0.2794)
			(stroke
				(width 0.1)
				(type default)
			)
			(layer "B.Fab")
		)
		(fp_line
			(start -0.12065 -0.2794)
			(end -0.12065 -0.3048)
			(stroke
				(width 0.1)
				(type default)
			)
			(layer "B.Fab")
		)
		(fp_line
			(start 0.12065 0.2794)
			(end 0.12065 0.3048)
			(stroke
				(width 0.1)
				(type default)
			)
			(layer "B.Fab")
		)
		(fp_line
			(start -0.120396 0.2794)
			(end 0.12065 0.2794)
			(stroke
				(width 0.1)
				(type default)
			)
			(layer "B.Fab")
		)
		(fp_line
			(start 0.67945 0.3048)
			(end 0.67945 -0.305054)
			(stroke
				(width 0.1)
				(type default)
			)
			(layer "B.Fab")
		)
		(fp_line
			(start 0.12065 0.3048)
			(end 0.67945 0.3048)
			(stroke
				(width 0.1)
				(type default)
			)
			(layer "B.Fab")
		)
		(fp_line
			(start -0.120396 0.3048)
			(end -0.120396 0.2794)
			(stroke
				(width 0.1)
				(type default)
			)
			(layer "B.Fab")
		)
		(fp_line
			(start -0.67945 0.3048)
			(end -0.120396 0.3048)
			(stroke
				(width 0.1)
				(type default)
			)
			(layer "B.Fab")
		)
		(pad "1" smd circle
			(at 0.40005 0 270)
			(size 0 0)
			(layers "B.Cu" "B.Mask" "B.Paste")
			(net "P12V_HSC_ADC_N")
		)
		(pad "2" smd circle
			(at -0.40005 0 270)
			(size 0 0)
			(layers "B.Cu" "B.Mask" "B.Paste")
			(net "P12V_HSC_SENSE2_R2_N")
		)
	)
)
